# S9S_MB_2U (Grand Teton) — schematic netlist excerpt (pin names and nets, part order shuffled) for the footprints in the layout excerpt that follows; sources: Cadence DE-HDL packaged netlist, KiCad conversion of 03242023_DA0F0TMBIJ0_F0T_Motherboard_J_brd_V01_OCP.brd

R220  Q_RES  100 1% CHIP  pkg 0402LF  page 122 : A = PVNN_TERM_CPU1 ; B = H_CPU1_MEMHOT_IN_LVC1_R1_N
R4630  Q_RES  0 5% CHIP  pkg 0402LF  page 248 : A = JTAG_BMC_SW_TDO_R ; B = JTAG_BMC_SW_TDO
PC1218  Q_CAP  22UF 16V 20% X6S  pkg C0805  page 262 : A = SW_P12V_AUX_P1V05_PCH_AUX_FLT ; B = GND

(kicad_pcb
	(version 20260206)
	(generator "pcbnew")
	(generator_version "10.0")
	(general
		(thickness 1.6)
		(legacy_teardrops no)
	)
	(paper "A4")
	(title_block
		(title "03242023_DA0F0TMBIJ0_F0T_Motherboard_J_brd_V01_OCP.brd")
		(comment 1 "Grand Teton / footprints 1038-1040 of 6105")
	)
	(layers
		(0 "F.Cu" signal "TOP")
		(4 "In1.Cu" signal "GND")
		(6 "In2.Cu" signal "IN1")
		(8 "In3.Cu" signal "GND1")
		(10 "In4.Cu" signal "IN2")
		(12 "In5.Cu" signal "GND2")
		(14 "In6.Cu" signal "IN3")
		(16 "In7.Cu" signal "GND3")
		(18 "In8.Cu" signal "VCC")
		(20 "In9.Cu" signal "VCC1")
		(22 "In10.Cu" signal "GND4")
		(24 "In11.Cu" signal "IN4")
		(26 "In12.Cu" signal "GND5")
		(28 "In13.Cu" signal "IN5")
		(30 "In14.Cu" signal "GND6")
		(32 "In15.Cu" signal "IN6")
		(34 "In16.Cu" signal "GND7")
		(2 "B.Cu" signal "BOTTOM")
		(9 "F.Adhes" user "F.Adhesive")
		(11 "B.Adhes" user "B.Adhesive")
		(13 "F.Paste" user "Package Geometry/Pastemask Top")
		(15 "B.Paste" user "Package Geometry/Pastemask Bottom")
		(5 "F.SilkS" user "Ref Des/Silkscreen Top")
		(7 "B.SilkS" user "Ref Des/Silkscreen Bottom")
		(1 "F.Mask" user "Board Geometry/Soldermask Top")
		(3 "B.Mask" user "Board Geometry/Soldermask Bottom")
		(17 "Dwgs.User" user "User.Drawings")
		(19 "Cmts.User" user "User.Comments")
		(21 "Eco1.User" user "User.Eco1")
		(23 "Eco2.User" user "User.Eco2")
		(25 "Edge.Cuts" user "Board Geometry/Outline")
		(27 "Margin" user)
		(31 "F.CrtYd" user "Package Geometry/Place Bound Top")
		(29 "B.CrtYd" user "Package Geometry/Place Bound Bottom")
		(35 "F.Fab" user "Ref Des/Assembly Top")
		(33 "B.Fab" user "Ref Des/Assembly Bottom")
	)
	(footprint ""
		(layer "F.Cu")
		(at 124.66574 -79.649828)
		(property "Reference" "R4630"
			(at 0 0 0)
			(layer "F.SilkS")
			(hide yes)
			(effects
				(font
					(size 1.27 1.27)
				)
			)
		)
		(property "Value" ""
			(at 0 0 0)
			(layer "F.Fab")
			(effects
				(font
					(size 1.27 1.27)
				)
			)
		)
		(duplicate_pad_numbers_are_jumpers no)
		(fp_line
			(start -0.7874 -0.4064)
			(end 0.7874 -0.4064)
			(stroke
				(width 0.1524)
				(type default)
			)
			(layer "F.SilkS")
		)
		(fp_line
			(start -0.7874 0.4064)
			(end -0.7874 -0.4064)
			(stroke
				(width 0.1524)
				(type default)
			)
			(layer "F.SilkS")
		)
		(fp_line
			(start 0.7874 -0.4064)
			(end 0.7874 0.4064)
			(stroke
				(width 0.1524)
				(type default)
			)
			(layer "F.SilkS")
		)
		(fp_line
			(start 0.7874 0.4064)
			(end -0.7874 0.4064)
			(stroke
				(width 0.1524)
				(type default)
			)
			(layer "F.SilkS")
		)
		(fp_line
			(start -0.67945 -0.305054)
			(end -0.12065 -0.305054)
			(stroke
				(width 0.1)
				(type default)
			)
			(layer "F.Fab")
		)
		(fp_line
			(start -0.67945 0.3048)
			(end -0.67945 -0.305054)
			(stroke
				(width 0.1)
				(type default)
			)
			(layer "F.Fab")
		)
		(fp_line
			(start -0.12065 -0.305054)
			(end -0.12065 -0.2794)
			(stroke
				(width 0.1)
				(type default)
			)
			(layer "F.Fab")
		)
		(fp_line
			(start -0.12065 -0.2794)
			(end 0.12065 -0.2794)
			(stroke
				(width 0.1)
				(type default)
			)
			(layer "F.Fab")
		)
		(fp_line
			(start -0.12065 0.2794)
			(end -0.12065 0.3048)
			(stroke
				(width 0.1)
				(type default)
			)
			(layer "F.Fab")
		)
		(fp_line
			(start -0.12065 0.3048)
			(end -0.67945 0.3048)
			(stroke
				(width 0.1)
				(type default)
			)
			(layer "F.Fab")
		)
		(fp_line
			(start 0.120396 0.2794)
			(end -0.12065 0.2794)
			(stroke
				(width 0.1)
				(type default)
			)
			(layer "F.Fab")
		)
		(fp_line
			(start 0.120396 0.3048)
			(end 0.120396 0.2794)
			(stroke
				(width 0.1)
				(type default)
			)
			(layer "F.Fab")
		)
		(fp_line
			(start 0.12065 -0.3048)
			(end 0.67945 -0.3048)
			(stroke
				(width 0.1)
				(type default)
			)
			(layer "F.Fab")
		)
		(fp_line
			(start 0.12065 -0.2794)
			(end 0.12065 -0.3048)
			(stroke
				(width 0.1)
				(type default)
			)
			(layer "F.Fab")
		)
		(fp_line
			(start 0.67945 -0.3048)
			(end 0.67945 0.3048)
			(stroke
				(width 0.1)
				(type default)
			)
			(layer "F.Fab")
		)
		(fp_line
			(start 0.67945 0.3048)
			(end 0.120396 0.3048)
			(stroke
				(width 0.1)
				(type default)
			)
			(layer "F.Fab")
		)
		(pad "1" smd circle
			(at -0.40005 0)
			(size 0 0)
			(layers "F.Cu" "F.Mask" "F.Paste")
			(net "JTAG_BMC_SW_TDO_R")
		)
		(pad "2" smd circle
			(at 0.40005 0)
			(size 0 0)
			(layers "F.Cu" "F.Mask" "F.Paste")
			(net "JTAG_BMC_SW_TDO")
		)
	)
	(footprint ""
		(layer "F.Cu")
		(at 201.02068 -101.145848 180)
		(property "Reference" "R220"
			(at 0 0 180)
			(layer "F.SilkS")
			(hide yes)
			(effects
				(font
					(size 1.27 1.27)
				)
			)
		)
		(property "Value" ""
			(at 0 0 180)
			(layer "F.Fab")
			(effects
				(font
					(size 1.27 1.27)
				)
			)
		)
		(duplicate_pad_numbers_are_jumpers no)
		(fp_line
			(start 0.7874 0.4064)
			(end -0.7874 0.4064)
			(stroke
				(width 0.1524)
				(type default)
			)
			(layer "F.SilkS")
		)
		(fp_line
			(start 0.7874 -0.4064)
			(end 0.7874 0.4064)
			(stroke
				(width 0.1524)
				(type default)
			)
			(layer "F.SilkS")
		)
		(fp_line
			(start -0.7874 0.4064)
			(end -0.7874 -0.4064)
			(stroke
				(width 0.1524)
				(type default)
			)
			(layer "F.SilkS")
		)
		(fp_line
			(start -0.7874 -0.4064)
			(end 0.7874 -0.4064)
			(stroke
				(width 0.1524)
				(type default)
			)
			(layer "F.SilkS")
		)
		(fp_line
			(start 0.67945 0.3048)
			(end 0.120396 0.3048)
			(stroke
				(width 0.1)
				(type default)
			)
			(layer "F.Fab")
		)
		(fp_line
			(start 0.67945 -0.3048)
			(end 0.67945 0.3048)
			(stroke
				(width 0.1)
				(type default)
			)
			(layer "F.Fab")
		)
		(fp_line
			(start 0.12065 -0.2794)
			(end 0.12065 -0.3048)
			(stroke
				(width 0.1)
				(type default)
			)
			(layer "F.Fab")
		)
		(fp_line
			(start 0.12065 -0.3048)
			(end 0.67945 -0.3048)
			(stroke
				(width 0.1)
				(type default)
			)
			(layer "F.Fab")
		)
		(fp_line
			(start 0.120396 0.3048)
			(end 0.120396 0.2794)
			(stroke
				(width 0.1)
				(type default)
			)
			(layer "F.Fab")
		)
		(fp_line
			(start 0.120396 0.2794)
			(end -0.12065 0.2794)
			(stroke
				(width 0.1)
				(type default)
			)
			(layer "F.Fab")
		)
		(fp_line
			(start -0.12065 0.3048)
			(end -0.67945 0.3048)
			(stroke
				(width 0.1)
				(type default)
			)
			(layer "F.Fab")
		)
		(fp_line
			(start -0.12065 0.2794)
			(end -0.12065 0.3048)
			(stroke
				(width 0.1)
				(type default)
			)
			(layer "F.Fab")
		)
		(fp_line
			(start -0.12065 -0.2794)
			(end 0.12065 -0.2794)
			(stroke
				(width 0.1)
				(type default)
			)
			(layer "F.Fab")
		)
		(fp_line
			(start -0.12065 -0.305054)
			(end -0.12065 -0.2794)
			(stroke
				(width 0.1)
				(type default)
			)
			(layer "F.Fab")
		)
		(fp_line
			(start -0.67945 0.3048)
			(end -0.67945 -0.305054)
			(stroke
				(width 0.1)
				(type default)
			)
			(layer "F.Fab")
		)
		(fp_line
			(start -0.67945 -0.305054)
			(end -0.12065 -0.305054)
			(stroke
				(width 0.1)
				(type default)
			)
			(layer "F.Fab")
		)
		(pad "1" smd circle
			(at -0.40005 0 180)
			(size 0 0)
			(layers "F.Cu" "F.Mask" "F.Paste")
			(net "PVNN_TERM_CPU1")
		)
		(pad "2" smd circle
			(at 0.40005 0 180)
			(size 0 0)
			(layers "F.Cu" "F.Mask" "F.Paste")
			(net "H_CPU1_MEMHOT_IN_LVC1_R1_N")
		)
	)
	(footprint ""
		(layer "F.Cu")
		(at 258.10845 -70.40626 -90)
		(property "Reference" "PC1218"
			(at 0 0 270)
			(layer "F.SilkS")
			(hide yes)
			(effects
				(font
					(size 1.27 1.27)
				)
			)
		)
		(property "Value" ""
			(at 0 0 270)
			(layer "F.Fab")
			(effects
				(font
					(size 1.27 1.27)
				)
			)
		)
		(duplicate_pad_numbers_are_jumpers no)
		(fp_line
			(start -1.524 0.762)
			(end -1.524 -0.762)
			(stroke
				(width 0.1524)
				(type default)
			)
			(layer "F.SilkS")
		)
		(fp_line
			(start 1.524 0.762)
			(end -1.524 0.762)
			(stroke
				(width 0.1524)
				(type default)
			)
			(layer "F.SilkS")
		)
		(fp_line
			(start -1.524 -0.762)
			(end 1.524 -0.762)
			(stroke
				(width 0.1524)
				(type default)
			)
			(layer "F.SilkS")
		)
		(fp_line
			(start 1.524 -0.762)
			(end 1.524 0.762)
			(stroke
				(width 0.1524)
				(type default)
			)
			(layer "F.SilkS")
		)
		(fp_line
			(start -1.1049 0.724916)
			(end 1.1049 0.724916)
			(stroke
				(width 0.1)
				(type default)
			)
			(layer "F.Fab")
		)
		(fp_line
			(start 1.1049 0.724916)
			(end 1.1049 -0.724916)
			(stroke
				(width 0.1)
				(type default)
			)
			(layer "F.Fab")
		)
		(fp_line
			(start -1.1049 -0.724916)
			(end -1.1049 0.724916)
			(stroke
				(width 0.1)
				(type default)
			)
			(layer "F.Fab")
		)
		(fp_line
			(start 1.1049 -0.724916)
			(end -1.1049 -0.724916)
			(stroke
				(width 0.1)
				(type default)
			)
			(layer "F.Fab")
		)
		(pad "1" smd rect
			(at -0.889 0 90)
			(size 1.016 1.27)
			(layers "F.Cu" "F.Mask" "F.Paste")
			(net "SW_P12V_AUX_P1V05_PCH_AUX_FLT")
		)
		(pad "2" smd rect
			(at 0.889 0 90)
			(size 1.016 1.27)
			(layers "F.Cu" "F.Mask" "F.Paste")
			(net "GND")
		)
	)
)
